# S9S_MB_2U (Grand Teton) — schematic parts with pin connectivity, parts 5876–5876 of 6093; source: Cadence DE-HDL packaged netlist (pstxprt.dat, pstxnet.dat, pstchip.dat)

U1  SOCKET4677_AZIF0045P001C01CS  SOCKET4677_AZIF0045-P001C01CS IO  pkg SOCKET4677_82X64-5XA_H466  page 44  (pins 4252-4578 of 4677)
  L48  VSS1670  POWER  = GND
  L50  VSS1672  POWER  = GND
  L52  VSS1673  POWER  = GND
  L54  VSS1674  POWER  = GND
  L56  VSS1676  POWER  = GND
  L58  VSS1634  POWER  = GND
  L60  VSS1677  POWER  = GND
  L62  VSS1678  POWER  = GND
  L64  VSS1679  POWER  = GND
  L66  VSS1680  POWER  = GND
  L68  VSS1681  POWER  = GND
  L70  VSS1640  POWER  = GND
  L72  VSS1682  POWER  = GND
  L74  VSS1683  POWER  = GND
  L76  VSS1684  POWER  = GND
  L78  VSS1685  POWER  = GND
  L80  UPI2_RX_DN5  IN  = UPI_CPU0_CPU1_P2P2_DN<5>
  L82  UPI2_RX_DP4  IN  = UPI_CPU0_CPU1_P2P2_DP<4>
  L84  VCCFA_EHV_FIVRA89  POWER  = PVCCFA_EHV_FIVRA_CPU1
  L86  PE4_TX_DN0  OUT  = P5E_CPU1_PE4_TX_DN<0>
  L88  VSS1646  POWER  = GND
  L90  VSS1648  POWER  = GND
  M2  UPI0_TX_DN1  OUT  = UPI_CPU1_CPU0_P0P1_DN<1>
  M4  VSS1652  POWER  = GND
  M6  UPI0_RX_DP1  IN  = UPI_CPU0_CPU1_P1P0_DP<1>
  M8  VSS1657  POWER  = GND
  M10  PE0_RX_DN1  IN  = P5E_CPU1_PE0_RX_DN<1>
  M12  VSS1649  POWER  = GND
  M14  PE0_TX_DP0  OUT  = P5E_CPU1_PE0_TX_DP<0>
  M16  DDR1_SB_DQ23  BI  = M_B_CPU1_SB_DQ<23>
  M18  DDR1_SB_DQS_DN7  BI  = M_B_CPU1_SB_DQS_DN<7>
  M20  DDR1_SB_DQ18  BI  = M_B_CPU1_SB_DQ<18>
  M22  DDR1_SB_DQ15  BI  = M_B_CPU1_SB_DQ<15>
  M24  DDR1_SB_DQS_DN6  BI  = M_B_CPU1_SB_DQS_DN<6>
  M26  DDR1_SB_DQ10  BI  = M_B_CPU1_SB_DQ<10>
  M28  DDR0_SB_DQ7  BI  = M_A_CPU1_SB_DQ<7>
  M30  DDR0_SB_DQS_DN5  BI  = M_A_CPU1_SB_DQS_DN<5>
  M32  DDR0_SB_DQ2  BI  = M_A_CPU1_SB_DQ<2>
  M34  DDR1_SB_ECC3  BI  = M_B_CPU1_SB_CB<3>
  M36  DDR1_SB_DQS_DP4  BI  = M_B_CPU1_SB_DQS_DP<4>
  M38  DDR1_SB_ECC6  BI  = M_B_CPU1_SB_CB<6>
  M40  DDR1_SB_CS_N3  OUT  = M_B_CPU1_SB_CS_N<3>
  M42  VSS1653  POWER  = GND
  M44  DDR1_SB_CA3  OUT  = M_B_CPU1_SB_CA<3>
  M47  DDR1_SA_CA5  OUT  = M_B_CPU1_SA_CA<5>
  M49  VSS1654  POWER  = GND
  M51  DDR1_SA_CS_N2  OUT  = M_B_CPU1_SA_CS_N<2>
  M53  DDR1_SA_ECC7  BI  = M_B_CPU1_SA_CB<7>
  M55  DDR1_SA_DQS_DN9  BI  = M_B_CPU1_SA_DQS_DN<9>
  M57  DDR1_SA_ECC2  BI  = M_B_CPU1_SA_CB<2>
  M59  DDR1_SA_DQ23  BI  = M_B_CPU1_SA_DQ<23>
  M61  DDR1_SA_DQS_DN7  BI  = M_B_CPU1_SA_DQS_DN<7>
  M63  DDR1_SA_DQ18  BI  = M_B_CPU1_SA_DQ<18>
  M65  DDR0_SA_DQ15  BI  = M_A_CPU1_SA_DQ<15>
  M67  DDR0_SA_DQS_DP6  BI  = M_A_CPU1_SA_DQS_DP<6>
  M69  DDR0_SA_DQ10  BI  = M_A_CPU1_SA_DQ<10>
  M71  DDR1_SA_DQ7  BI  = M_B_CPU1_SA_DQ<7>
  M73  DDR1_SA_DQS_DN5  BI  = M_B_CPU1_SA_DQS_DN<5>
  M75  DDR1_SA_DQ2  BI  = M_B_CPU1_SA_DQ<2>
  M77  DDR0_SA_DQ2  BI  = M_A_CPU1_SA_DQ<2>
  M79  UPI2_RX_DP3  IN  = UPI_CPU0_CPU1_P2P2_DP<3>
  M81  VSS1686  POWER  = GND
  M83  VSS1687  POWER  = GND
  M85  VCCFA_EHV_FIVRA90  POWER  = PVCCFA_EHV_FIVRA_CPU1
  M87  PE4_TX_DP0  OUT  = P5E_CPU1_PE4_TX_DP<0>
  M89  VCCFA_EHV_FIVRA91  POWER  = PVCCFA_EHV_FIVRA_CPU1
  N1  UPI0_TX_DN2  OUT  = UPI_CPU1_CPU0_P0P1_DN<2>
  N3  VCCFA_EHV8  POWER  = PVCCFA_EHV_CPU1
  N5  UPI0_RX_DN1  IN  = UPI_CPU0_CPU1_P1P0_DN<1>
  N7  VCCFA_EHV_FIVRA93  POWER  = PVCCFA_EHV_FIVRA_CPU1
  N9  PE0_RX_DP1  IN  = P5E_CPU1_PE0_RX_DP<1>
  N11  VCCFA_EHV_FIVRA92  POWER  = PVCCFA_EHV_FIVRA_CPU1
  N13  PE0_TX_DN0  OUT  = P5E_CPU1_PE0_TX_DN<0>
  N15  VSS1688  POWER  = GND
  N17  DDR1_SB_DQ22  BI  = M_B_CPU1_SB_DQ<22>
  N19  DDR1_SB_DQ19  BI  = M_B_CPU1_SB_DQ<19>
  N21  VSS1664  POWER  = GND
  N23  DDR1_SB_DQ14  BI  = M_B_CPU1_SB_DQ<14>
  N25  DDR1_SB_DQ11  BI  = M_B_CPU1_SB_DQ<11>
  N27  VSS1689  POWER  = GND
  N29  DDR0_SB_DQ6  BI  = M_A_CPU1_SB_DQ<6>
  N31  DDR0_SB_DQ3  BI  = M_A_CPU1_SB_DQ<3>
  N33  VSS1691  POWER  = GND
  N35  DDR1_SB_ECC2  BI  = M_B_CPU1_SB_CB<2>
  N37  DDR1_SB_ECC7  BI  = M_B_CPU1_SB_CB<7>
  N39  VSS1669  POWER  = GND
  N41  DDR1_SB_CS_N2  OUT  = M_B_CPU1_SB_CS_N<2>
  N43  DDR1_SB_CA5  OUT  = M_B_CPU1_SB_CA<5>
  N45  VSS1692  POWER  = GND
  N48  DDR1_SA_CA3  OUT  = M_B_CPU1_SA_CA<3>
  N50  DDR1_SA_CS_N3  OUT  = M_B_CPU1_SA_CS_N<3>
  N52  VSS1693  POWER  = GND
  N54  DDR1_SA_ECC6  BI  = M_B_CPU1_SA_CB<6>
  N56  DDR1_SA_ECC3  BI  = M_B_CPU1_SA_CB<3>
  N58  VSS1694  POWER  = GND
  N60  DDR1_SA_DQ22  BI  = M_B_CPU1_SA_DQ<22>
  N62  DDR1_SA_DQ19  BI  = M_B_CPU1_SA_DQ<19>
  N64  VSS1675  POWER  = GND
  N66  DDR0_SA_DQ14  BI  = M_A_CPU1_SA_DQ<14>
  N68  DDR0_SA_DQ11  BI  = M_A_CPU1_SA_DQ<11>
  N70  VSS1695  POWER  = GND
  N72  DDR1_SA_DQ6  BI  = M_B_CPU1_SA_DQ<6>
  N74  DDR1_SA_DQ3  BI  = M_B_CPU1_SA_DQ<3>
  N76  VSS1696  POWER  = GND
  N78  VSS1698  POWER  = GND
  N80  VSS1700  POWER  = GND
  N82  VSS1701  POWER  = GND
  N84  VSS1702  POWER  = GND
  N86  PE4_TX_DP1  OUT  = P5E_CPU1_PE4_TX_DP<1>
  N88  VSS1703  POWER  = GND
  N90  PE4_RX_DP1  IN  = P5E_CPU1_PE4_RX_DP<1>
  P2  UPI0_TX_DP2  OUT  = UPI_CPU1_CPU0_P0P1_DP<2>
  P4  VSS1716  POWER  = GND
  P6  UPI0_RX_DN2  IN  = UPI_CPU0_CPU1_P1P0_DN<2>
  P8  VSS1729  POWER  = GND
  P10  PE0_RX_DN2  IN  = P5E_CPU1_PE0_RX_DN<2>
  P12  VSS1705  POWER  = GND
  P14  PE0_TX_DN1  OUT  = P5E_CPU1_PE0_TX_DN<1>
  P16  VSS1706  POWER  = GND
  P18  DDR1_SB_DQS_DP7  BI  = M_B_CPU1_SB_DQS_DP<7>
  P20  VSS1707  POWER  = GND
  P22  VSS1708  POWER  = GND
  P24  DDR1_SB_DQS_DP6  BI  = M_B_CPU1_SB_DQS_DP<6>
  P26  VSS1709  POWER  = GND
  P28  VSS1710  POWER  = GND
  P30  DDR0_SB_DQS_DP5  BI  = M_A_CPU1_SB_DQS_DP<5>
  P32  VSS1690  POWER  = GND
  P34  VSS1712  POWER  = GND
  P36  DDR1_SB_DQS_DN4  BI  = M_B_CPU1_SB_DQS_DN<4>
  P38  VSS1713  POWER  = GND
  P40  VSS1717  POWER  = GND
  P42  DDR1_SB_PAR  OUT  = M_B_CPU1_SB_PAR
  P44  VSS1718  POWER  = GND
  P47  VSS1719  POWER  = GND
  P49  DDR1_SA_CA1  OUT  = M_B_CPU1_SA_CA<1>
  P51  VSS1697  POWER  = GND
  P53  VSS1720  POWER  = GND
  P55  DDR1_SA_DQS_DP9  BI  = M_B_CPU1_SA_DQS_DP<9>
  P57  VSS1699  POWER  = GND
  P59  VSS1721  POWER  = GND
  P61  DDR1_SA_DQS_DP7  BI  = M_B_CPU1_SA_DQS_DP<7>
  P63  VSS1722  POWER  = GND
  P65  VSS1724  POWER  = GND
  P67  DDR0_SA_DQS_DN6  BI  = M_A_CPU1_SA_DQS_DN<6>
  P69  VSS1725  POWER  = GND
  P71  VSS1704  POWER  = GND
  P73  DDR1_SA_DQS_DP5  BI  = M_B_CPU1_SA_DQS_DP<5>
  P75  VSS1726  POWER  = GND
  P77  VSS1727  POWER  = GND
  P79  VCCFA_EHV_FIVRA94  POWER  = PVCCFA_EHV_FIVRA_CPU1
  P81  UPI2_TX_DN5  OUT  = UPI_CPU1_CPU0_P2P2_DN<5>
  P83  UPI2_TX_DP6  OUT  = UPI_CPU1_CPU0_P2P2_DP<6>
  P85  PE4_TX_DN1  OUT  = P5E_CPU1_PE4_TX_DN<1>
  P87  VSS1731  POWER  = GND
  P89  PE4_RX_DN1  IN  = P5E_CPU1_PE4_RX_DN<1>
  P91  VSS1732  POWER  = GND
  R1  VSS1711  POWER  = GND
  R3  UPI0_TX_DP3  OUT  = UPI_CPU1_CPU0_P0P1_DP<3>
  R5  VSS1745  POWER  = GND
  R7  UPI0_RX_DP2  IN  = UPI_CPU0_CPU1_P1P0_DP<2>
  R9  VSS1759  POWER  = GND
  R11  PE0_RX_DP2  IN  = P5E_CPU1_PE0_RX_DP<2>
  R13  VSS1733  POWER  = GND
  R15  PE0_TX_DP1  OUT  = P5E_CPU1_PE0_TX_DP<1>
  R17  VSS1734  POWER  = GND
  R19  VSS1714  POWER  = GND
  R21  DDR2_SB_DQS_DN2  BI  = M_C_CPU1_SB_DQS_DN<2>
  R23  VSS1715  POWER  = GND
  R25  VSS1735  POWER  = GND
  R27  DDR1_SB_DQS_DN0  BI  = M_B_CPU1_SB_DQS_DN<0>
  R29  VSS1736  POWER  = GND
  R31  VSS1737  POWER  = GND
  R33  DDR2_SB_DQS_DN9  BI  = M_C_CPU1_SB_DQS_DN<9>
  R35  VSS1738  POWER  = GND
  R37  VSS1742  POWER  = GND
  R39  DDR2_SB_CA6  OUT  = M_C_CPU1_SB_CA<6>
  R41  VSS1743  POWER  = GND
  R43  VSS1744  POWER  = GND
  R45  DDR1_CLK_DN0  OUT  = M_B_CPU1_CLK_DN<0>
  R48  VSS1723  POWER  = GND
  R50  VSS1747  POWER  = GND
  R52  DDR2_SA_CA0  OUT  = M_C_CPU1_SA_CA<0>
  R54  VSS1748  POWER  = GND
  R56  VSS1751  POWER  = GND
  R58  DDR1_SA_DQS_DN3  BI  = M_B_CPU1_SA_DQS_DN<3>
  R60  VSS1728  POWER  = GND
  R62  VSS1752  POWER  = GND
  R64  DDR2_SA_DQS_DN2  BI  = M_C_CPU1_SA_DQS_DN<2>
  R66  VSS1730  POWER  = GND
  R68  VSS1753  POWER  = GND
  R70  DDR1_SA_DQS_DN1  BI  = M_B_CPU1_SA_DQS_DN<1>
  R72  VSS1754  POWER  = GND
  R74  VSS1755  POWER  = GND
  R76  DDR2_SA_DQS_DN0  BI  = M_C_CPU1_SA_DQS_DN<0>
  R78  VSS1756  POWER  = GND
  R80  VCCFA_EHV_FIVRA95  POWER  = PVCCFA_EHV_FIVRA_CPU1
  R82  UPI2_TX_DN6  OUT  = UPI_CPU1_CPU0_P2P2_DN<6>
  R84  VSS1757  POWER  = GND
  R86  PE4_TX_DN2  OUT  = P5E_CPU1_PE4_TX_DN<2>
  R88  VSS1758  POWER  = GND
  R90  PE4_RX_DP2  IN  = P5E_CPU1_PE4_RX_DP<2>
  T2  UPI0_TX_DN3  OUT  = UPI_CPU1_CPU0_P0P1_DN<3>
  T4  VSS1762  POWER  = GND
  T6  UPI0_RX_DP3  IN  = UPI_CPU0_CPU1_P1P0_DP<3>
  T8  VSS1769  POWER  = GND
  T10  PE0_RX_DN3  IN  = P5E_CPU1_PE0_RX_DN<3>
  T12  VSS1739  POWER  = GND
  T14  PE0_TX_DP2  OUT  = P5E_CPU1_PE0_TX_DP<2>
  T16  VSS1740  POWER  = GND
  T18  VSS1741  POWER  = GND
  T20  DDR2_SB_DQ20  BI  = M_C_CPU1_SB_DQ<20>
  T22  DDR2_SB_DQ17  BI  = M_C_CPU1_SB_DQ<17>
  T24  VSS1760  POWER  = GND
  T26  DDR1_SB_DQ4  BI  = M_B_CPU1_SB_DQ<4>
  T28  DDR1_SB_DQ1  BI  = M_B_CPU1_SB_DQ<1>
  T30  VSS1761  POWER  = GND
  T32  DDR2_SB_ECC0  BI  = M_C_CPU1_SB_CB<0>
  T34  DDR2_SB_ECC5  BI  = M_C_CPU1_SB_CB<5>
  T36  VSS1746  POWER  = GND
  T38  DDR2_SB_CS_N0  OUT  = M_C_CPU1_SB_CS_N<0>
  T40  DDR2_SB_CA4  OUT  = M_C_CPU1_SB_CA<4>
  T42  VSS1763  POWER  = GND
  T44  DDR1_SB_CA0  OUT  = M_B_CPU1_SB_CA<0>
  T47  DDR2_SA_PAR  OUT  = M_C_CPU1_SA_PAR
  T49  VSS1749  POWER  = GND
  T51  DDR2_SA_CA2  OUT  = M_C_CPU1_SA_CA<2>
  T53  DDR2_SA_CS_N1  OUT  = M_C_CPU1_SA_CS_N<1>
  T55  VSS1750  POWER  = GND
  T57  DDR1_SA_DQ28  BI  = M_B_CPU1_SA_DQ<28>
  T59  DDR1_SA_DQ25  BI  = M_B_CPU1_SA_DQ<25>
  T61  VSS1764  POWER  = GND
  T63  DDR2_SA_DQ20  BI  = M_C_CPU1_SA_DQ<20>
  T65  DDR2_SA_DQ17  BI  = M_C_CPU1_SA_DQ<17>
  T67  VSS1765  POWER  = GND
  T69  DDR1_SA_DQ12  BI  = M_B_CPU1_SA_DQ<12>
  T71  DDR1_SA_DQ9  BI  = M_B_CPU1_SA_DQ<9>
  T73  VSS1767  POWER  = GND
  T75  DDR2_SA_DQ4  BI  = M_C_CPU1_SA_DQ<4>
  T77  DDR2_SA_DQ1  BI  = M_C_CPU1_SA_DQ<1>
  T79  VSS1768  POWER  = GND
  T81  UPI2_TX_DP5  OUT  = UPI_CPU1_CPU0_P2P2_DP<5>
  T83  VSS1770  POWER  = GND
  T85  VCCFA_EHV_FIVRA96  POWER  = PVCCFA_EHV_FIVRA_CPU1
  T87  PE4_TX_DP2  OUT  = P5E_CPU1_PE4_TX_DP<2>
  T89  VCCFA_EHV_FIVRA97  POWER  = PVCCFA_EHV_FIVRA_CPU1
  T91  PE4_RX_DN2  IN  = P5E_CPU1_PE4_RX_DN<2>
  U1  UPI0_TX_DN4  OUT  = UPI_CPU1_CPU0_P0P1_DN<4>
  U3  VCCFA_EHV9  POWER  = PVCCFA_EHV_CPU1
  U5  UPI0_RX_DN3  IN  = UPI_CPU0_CPU1_P1P0_DN<3>
  U7  VCCFA_EHV_FIVRA100  POWER  = PVCCFA_EHV_FIVRA_CPU1
  U9  PE0_RX_DP3  IN  = P5E_CPU1_PE0_RX_DP<3>
  U11  VCCFA_EHV_FIVRA98  POWER  = PVCCFA_EHV_FIVRA_CPU1
  U13  PE0_TX_DN2  OUT  = P5E_CPU1_PE0_TX_DN<2>
  U15  VCCFA_EHV_FIVRA99  POWER  = PVCCFA_EHV_FIVRA_CPU1
  U17  RSVD164  BI  = NC_CPU1_HBM0_VIEWDIG0
  U19  DDR2_SB_DQ21  BI  = M_C_CPU1_SB_DQ<21>
  U21  DDR2_SB_DQS_DP2  BI  = M_C_CPU1_SB_DQS_DP<2>
  U23  DDR2_SB_DQ16  BI  = M_C_CPU1_SB_DQ<16>
  U25  DDR1_SB_DQ5  BI  = M_B_CPU1_SB_DQ<5>
  U27  DDR1_SB_DQS_DP0  BI  = M_B_CPU1_SB_DQS_DP<0>
  U29  DDR1_SB_DQ0  BI  = M_B_CPU1_SB_DQ<0>
  U31  DDR2_SB_ECC1  BI  = M_C_CPU1_SB_CB<1>
  U33  DDR2_SB_DQS_DP9  BI  = M_C_CPU1_SB_DQS_DP<9>
  U35  DDR2_SB_ECC4  BI  = M_C_CPU1_SB_CB<4>
  U37  DDR2_SB_CS_N1  OUT  = M_C_CPU1_SB_CS_N<1>
  U39  VSS1771  POWER  = GND
  U41  DDR2_SB_CA2  OUT  = M_C_CPU1_SB_CA<2>
  U43  DDR1_SB_CA1  OUT  = M_B_CPU1_SB_CA<1>
  U45  DDR1_CLK_DP0  OUT  = M_B_CPU1_CLK_DP<0>
  U48  DDR2_SA_CA6  OUT  = M_C_CPU1_SA_CA<6>
  U50  DDR2_SA_CA4  OUT  = M_C_CPU1_SA_CA<4>
  U52  VSS1766  POWER  = GND
  U54  DDR2_SA_CS_N0  OUT  = M_C_CPU1_SA_CS_N<0>
  U56  DDR1_SA_DQ29  BI  = M_B_CPU1_SA_DQ<29>
  U58  DDR1_SA_DQS_DP3  BI  = M_B_CPU1_SA_DQS_DP<3>
  U60  DDR1_SA_DQ24  BI  = M_B_CPU1_SA_DQ<24>
  U62  DDR2_SA_DQ21  BI  = M_C_CPU1_SA_DQ<21>
  U64  DDR2_SA_DQS_DP2  BI  = M_C_CPU1_SA_DQS_DP<2>
  U66  DDR2_SA_DQ16  BI  = M_C_CPU1_SA_DQ<16>
  U68  DDR1_SA_DQ13  BI  = M_B_CPU1_SA_DQ<13>
  U70  DDR1_SA_DQS_DP1  BI  = M_B_CPU1_SA_DQS_DP<1>
  U72  DDR1_SA_DQ8  BI  = M_B_CPU1_SA_DQ<8>
  U74  DDR2_SA_DQ5  BI  = M_C_CPU1_SA_DQ<5>
  U76  DDR2_SA_DQS_DP0  BI  = M_C_CPU1_SA_DQS_DP<0>
  U78  DDR2_SA_DQ0  BI  = M_C_CPU1_SA_DQ<0>
  U80  UPI2_TX_DN7  OUT  = UPI_CPU1_CPU0_P2P2_DN<7>
  U82  VSS1772  POWER  = GND
  U84  VSS1773  POWER  = GND
  U86  PE4_TX_DN3  OUT  = P5E_CPU1_PE4_TX_DN<3>
  U88  VSS1774  POWER  = GND
  U90  PE4_RX_DP3  IN  = P5E_CPU1_PE4_RX_DP<3>
  V2  UPI0_TX_DP4  OUT  = UPI_CPU1_CPU0_P0P1_DP<4>
  V4  VSS1788  POWER  = GND
  V6  UPI0_RX_DN4  IN  = UPI_CPU0_CPU1_P1P0_DN<4>
  V8  VSS1812  POWER  = GND
  V10  PE0_RX_DN4  IN  = P5E_CPU1_PE0_RX_DN<4>
  V12  VSS1775  POWER  = GND
  V14  PE0_TX_DN3  OUT  = P5E_CPU1_PE0_TX_DN<3>
  V16  VSS1776  POWER  = GND
  V18  VSS1777  POWER  = GND
  V20  VSS1778  POWER  = GND
  V22  VSS1779  POWER  = GND
  V24  VSS1780  POWER  = GND
  V26  VSS1781  POWER  = GND
  V28  VSS1782  POWER  = GND
  V30  VSS1783  POWER  = GND
  V32  VSS1784  POWER  = GND
  V34  VSS1785  POWER  = GND
  V36  VSS1786  POWER  = GND
  V38  VSS1787  POWER  = GND
  V40  VSS1790  POWER  = GND
  V42  VSS1791  POWER  = GND
  V44  VSS1792  POWER  = GND
  V47  VSS1793  POWER  = GND
  V49  VSS1789  POWER  = GND
  V51  VSS1794  POWER  = GND
  V53  VSS1795  POWER  = GND
  V55  VSS1796  POWER  = GND
  V57  VSS1797  POWER  = GND
  V59  VSS1798  POWER  = GND
  V61  VSS1799  POWER  = GND
  V63  VSS1802  POWER  = GND
  V65  VSS1803  POWER  = GND
  V67  VSS1804  POWER  = GND
  V69  VSS1805  POWER  = GND
  V71  VSS1800  POWER  = GND
  V73  VSS1801  POWER  = GND
